(kicad_pcb
	(version 20260206)
	(generator "pcbnew")
	(generator_version "10.0")
	(general
		(thickness 1.6)
		(legacy_teardrops no)
	)
	(paper "A4")
	(title_block
		(title "timecard-production-celestica-r4006 — R4006-B0001-02_R01.brd")
		(comment 1 "Time Appliance Project (Time Card) / footprints 687-691 of 1113")
	)
	(layers
		(0 "F.Cu" signal "TOP")
		(4 "In1.Cu" signal "L02_GND1")
		(6 "In2.Cu" signal "L03_SIG1")
		(8 "In3.Cu" signal "L04_GND2")
		(10 "In4.Cu" signal "L05_VCC1")
		(12 "In5.Cu" signal "L06_VCC2")
		(14 "In6.Cu" signal "L07_GND3")
		(16 "In7.Cu" signal "L08_SIG2")
		(18 "In8.Cu" signal "L09_GND4")
		(2 "B.Cu" signal "BOTTOM")
		(9 "F.Adhes" user "F.Adhesive")
		(11 "B.Adhes" user "B.Adhesive")
		(13 "F.Paste" user "Package Geometry/Pastemask Top")
		(15 "B.Paste" user "Package Geometry/Pastemask Bottom")
		(5 "F.SilkS" user "Ref Des/Silkscreen Top")
		(7 "B.SilkS" user "Ref Des/Silkscreen Bottom")
		(1 "F.Mask" user "Board Geometry/Soldermask Top")
		(3 "B.Mask" user "Board Geometry/Soldermask Bottom")
		(17 "Dwgs.User" user "User.Drawings")
		(19 "Cmts.User" user "User.Comments")
		(21 "Eco1.User" user "User.Eco1")
		(23 "Eco2.User" user "User.Eco2")
		(25 "Edge.Cuts" user "Board Geometry/Outline")
		(27 "Margin" user)
		(31 "F.CrtYd" user "Package Geometry/Place Bound Top")
		(29 "B.CrtYd" user "Package Geometry/Place Bound Bottom")
		(35 "F.Fab" user "Ref Des/Assembly Top")
		(33 "B.Fab" user "Ref Des/Assembly Bottom")
	)
	(footprint ""
		(layer "B.Cu")
		(at 100.347018 -41.823132 180)
		(property "Reference" "C209"
			(at 42.435018 -1.214882 0)
			(unlocked yes)
			(layer "B.SilkS")
			(effects
				(font
					(size 0.635 0.4064)
					(thickness 0.1524)
				)
				(justify mirror)
			)
		)
		(property "Value" "VAL*"
			(at 0 3.718306 180)
			(unlocked yes)
			(layer "B.Fab")
			(hide yes)
			(effects
				(font
					(size 0.7874 0.5842)
					(thickness 0.127)
				)
				(justify mirror)
			)
		)
		(property "Tolerance" "TOL*"
			(at 0 4.861306 180)
			(unlocked yes)
			(layer "Cmts.User")
			(hide yes)
			(effects
				(font
					(size 0.7874 0.5842)
					(thickness 0.127)
				)
				(justify mirror)
			)
		)
		(property "User Part Number" "PARTNUM*"
			(at 0 2.575306 180)
			(unlocked yes)
			(layer "Cmts.User")
			(hide yes)
			(effects
				(font
					(size 0.7874 0.5842)
					(thickness 0.127)
				)
				(justify mirror)
			)
		)
		(property "Device Type" "CAPACITOR-G105-0B104-CK,0.1UF,A"
			(at 0 1.432306 180)
			(unlocked yes)
			(layer "B.Fab")
			(hide yes)
			(effects
				(font
					(size 0.7874 0.5842)
					(thickness 0.127)
				)
				(justify mirror)
			)
		)
		(duplicate_pad_numbers_are_jumpers no)
		(fp_line
			(start 0.970026 0.4699)
			(end 0.970026 -0.4699)
			(stroke
				(width 0.1)
				(type default)
			)
			(layer "B.SilkS")
		)
		(fp_line
			(start 0.970026 -0.4699)
			(end -0.970026 -0.4699)
			(stroke
				(width 0.1)
				(type default)
			)
			(layer "B.SilkS")
		)
		(fp_line
			(start -0.970026 0.4699)
			(end 0.970026 0.4699)
			(stroke
				(width 0.1)
				(type default)
			)
			(layer "B.SilkS")
		)
		(fp_line
			(start -0.970026 -0.4699)
			(end -0.970026 0.4699)
			(stroke
				(width 0.1)
				(type default)
			)
			(layer "B.SilkS")
		)
		(fp_poly
			(pts
				(xy 0.970026 0.4699) (xy -0.970026 0.4699) (xy -0.970026 -0.4699) (xy 0.970026 -0.4699)
			)
			(stroke
				(width 0)
				(type default)
			)
			(fill no)
			(layer "B.CrtYd")
		)
		(fp_line
			(start 0.508 0.3048)
			(end 0.508 -0.3048)
			(stroke
				(width 0.1)
				(type default)
			)
			(layer "B.Fab")
		)
		(fp_line
			(start 0.508 -0.3048)
			(end -0.508 -0.3048)
			(stroke
				(width 0.1)
				(type default)
			)
			(layer "B.Fab")
		)
		(fp_line
			(start -0.508 0.3048)
			(end 0.508 0.3048)
			(stroke
				(width 0.1)
				(type default)
			)
			(layer "B.Fab")
		)
		(fp_line
			(start -0.508 -0.3048)
			(end -0.508 0.3048)
			(stroke
				(width 0.1)
				(type default)
			)
			(layer "B.Fab")
		)
		(pad "1" smd circle
			(at 0.500126 0)
			(size 0.635 0.635)
			(layers "B.Cu" "B.Mask" "B.Paste")
			(net "FPGA_MGTAVTT")
		)
		(pad "2" smd circle
			(at -0.500126 0)
			(size 0.635 0.635)
			(layers "B.Cu" "B.Mask" "B.Paste")
			(net "SG")
		)
	)
	(footprint ""
		(layer "B.Cu")
		(at 89.408 -34.417 90)
		(property "Reference" "C136"
			(at -3.937 0.10033 270)
			(unlocked yes)
			(layer "B.SilkS")
			(effects
				(font
					(size 0.7874 0.5842)
					(thickness 0.1524)
				)
				(justify mirror)
			)
		)
		(property "Value" "VAL*"
			(at -0.0762 2.067306 90)
			(unlocked yes)
			(layer "B.Fab")
			(hide yes)
			(effects
				(font
					(size 0.7874 0.5842)
					(thickness 0.1524)
				)
				(justify mirror)
			)
		)
		(property "Tolerance" "TOL*"
			(at -0.0762 3.032506 90)
			(unlocked yes)
			(layer "Cmts.User")
			(hide yes)
			(effects
				(font
					(size 0.7874 0.5842)
					(thickness 0.1524)
				)
				(justify mirror)
			)
		)
		(property "User Part Number" "PARTNUM*"
			(at -0.1016 4.023106 90)
			(unlocked yes)
			(layer "Cmts.User")
			(hide yes)
			(effects
				(font
					(size 0.7874 0.5842)
					(thickness 0.1524)
				)
				(justify mirror)
			)
		)
		(property "Device Type" "CAPACITOR-G105-0B104-CK,0.1UF,A"
			(at -0.0508 1.127506 90)
			(unlocked yes)
			(layer "B.Fab")
			(hide yes)
			(effects
				(font
					(size 0.7874 0.5842)
					(thickness 0.1524)
				)
				(justify mirror)
			)
		)
		(duplicate_pad_numbers_are_jumpers no)
		(fp_line
			(start 1.143 -0.5588)
			(end 1.143 0.5588)
			(stroke
				(width 0.1)
				(type default)
			)
			(layer "B.SilkS")
		)
		(fp_line
			(start -1.143 -0.5588)
			(end 1.143 -0.5588)
			(stroke
				(width 0.1)
				(type default)
			)
			(layer "B.SilkS")
		)
		(fp_line
			(start 1.143 0.5588)
			(end -1.143 0.5588)
			(stroke
				(width 0.1)
				(type default)
			)
			(layer "B.SilkS")
		)
		(fp_line
			(start -1.143 0.5588)
			(end -1.143 -0.5588)
			(stroke
				(width 0.1)
				(type default)
			)
			(layer "B.SilkS")
		)
		(fp_rect
			(start 1.143 0.5588)
			(end -1.143 -0.5588)
			(stroke
				(width 0)
				(type default)
			)
			(fill no)
			(layer "B.CrtYd")
		)
		(fp_line
			(start 0.508 -0.3048)
			(end 0.508 0.3048)
			(stroke
				(width 0.1)
				(type default)
			)
			(layer "B.Fab")
		)
		(fp_line
			(start -0.508 -0.3048)
			(end 0.508 -0.3048)
			(stroke
				(width 0.1)
				(type default)
			)
			(layer "B.Fab")
		)
		(fp_line
			(start 0.508 0.3048)
			(end -0.508 0.3048)
			(stroke
				(width 0.1)
				(type default)
			)
			(layer "B.Fab")
		)
		(fp_line
			(start -0.508 0.3048)
			(end -0.508 -0.3048)
			(stroke
				(width 0.1)
				(type default)
			)
			(layer "B.Fab")
		)
		(pad "1" smd rect
			(at 0.5334 0 270)
			(size 0.7112 0.6096)
			(layers "B.Cu" "B.Mask" "B.Paste")
			(net "XP1R2V_FPGA")
		)
		(pad "2" smd rect
			(at -0.5334 0 270)
			(size 0.7112 0.6096)
			(layers "B.Cu" "B.Mask" "B.Paste")
			(net "SG")
		)
		(zone
			(layer "B.Cu")
			(hatch none 0.5)
			(connect_pads
				(clearance 0)
			)
			(min_thickness 0.25)
			(keepout
				(tracks allowed)
				(vias not_allowed)
				(pads allowed)
				(copperpour not_allowed)
				(footprints allowed)
			)
			(placement
				(enabled no)
				(sheetname "")
			)
			(fill
				(thermal_gap 0.5)
				(thermal_bridge_width 0.5)
				(island_removal_mode 0)
			)
			(polygon
				(pts
					(xy 89.7128 -34.4932) (xy 89.1032 -34.4932) (xy 89.1032 -34.3408) (xy 89.7128 -34.3408)
				)
			)
		)
	)
	(footprint ""
		(layer "B.Cu")
		(at 27.559 -91.059 -90)
		(property "Reference" "C98"
			(at -2.794 -0.21463 270)
			(unlocked yes)
			(layer "B.SilkS")
			(effects
				(font
					(size 0.7874 0.5842)
					(thickness 0.1524)
				)
				(justify mirror)
			)
		)
		(property "Value" "VAL*"
			(at -0.02032 2.13233 270)
			(unlocked yes)
			(layer "B.Fab")
			(hide yes)
			(effects
				(font
					(size 0.7874 0.5842)
					(thickness 0.1524)
				)
				(justify mirror)
			)
		)
		(property "Tolerance" "TOL*"
			(at -0.044704 3.05435 270)
			(unlocked yes)
			(layer "Cmts.User")
			(hide yes)
			(effects
				(font
					(size 0.7874 0.5842)
					(thickness 0.1524)
				)
				(justify mirror)
			)
		)
		(property "User Part Number" "PARTNUM*"
			(at -0.02032 4.024884 270)
			(unlocked yes)
			(layer "Cmts.User")
			(hide yes)
			(effects
				(font
					(size 0.7874 0.5842)
					(thickness 0.1524)
				)
				(justify mirror)
			)
		)
		(property "Device Type" "CAPACITOR-G105-0F475-BM,4.7UF,A"
			(at -0.008382 1.210564 270)
			(unlocked yes)
			(layer "B.Fab")
			(hide yes)
			(effects
				(font
					(size 0.7874 0.5842)
					(thickness 0.1524)
				)
				(justify mirror)
			)
		)
		(duplicate_pad_numbers_are_jumpers no)
		(fp_line
			(start -1.143 0.5588)
			(end -1.143 -0.5588)
			(stroke
				(width 0.1)
				(type default)
			)
			(layer "B.SilkS")
		)
		(fp_line
			(start 1.143 0.5588)
			(end -1.143 0.5588)
			(stroke
				(width 0.1)
				(type default)
			)
			(layer "B.SilkS")
		)
		(fp_line
			(start -1.143 -0.5588)
			(end 1.143 -0.5588)
			(stroke
				(width 0.1)
				(type default)
			)
			(layer "B.SilkS")
		)
		(fp_line
			(start 1.143 -0.5588)
			(end 1.143 0.5588)
			(stroke
				(width 0.1)
				(type default)
			)
			(layer "B.SilkS")
		)
		(fp_poly
			(pts
				(xy 1.143 0.5588) (xy -1.143 0.5588) (xy -1.143 -0.5588) (xy 1.143 -0.5588)
			)
			(stroke
				(width 0)
				(type default)
			)
			(fill no)
			(layer "B.CrtYd")
		)
		(fp_line
			(start -0.508 0.3048)
			(end -0.508 -0.3048)
			(stroke
				(width 0.1)
				(type default)
			)
			(layer "B.Fab")
		)
		(fp_line
			(start 0.508 0.3048)
			(end -0.508 0.3048)
			(stroke
				(width 0.1)
				(type default)
			)
			(layer "B.Fab")
		)
		(fp_line
			(start -0.508 -0.3048)
			(end 0.508 -0.3048)
			(stroke
				(width 0.1)
				(type default)
			)
			(layer "B.Fab")
		)
		(fp_line
			(start 0.508 -0.3048)
			(end 0.508 0.3048)
			(stroke
				(width 0.1)
				(type default)
			)
			(layer "B.Fab")
		)
		(pad "1" smd rect
			(at 0.5334 0 90)
			(size 0.7112 0.6096)
			(layers "B.Cu" "B.Mask" "B.Paste")
			(net "XP3R3V_VPLL")
		)
		(pad "2" smd rect
			(at -0.5334 0 90)
			(size 0.7112 0.6096)
			(layers "B.Cu" "B.Mask" "B.Paste")
			(net "SG")
		)
		(zone
			(layer "B.Cu")
			(hatch none 0.5)
			(connect_pads
				(clearance 0)
			)
			(min_thickness 0.25)
			(keepout
				(tracks allowed)
				(vias not_allowed)
				(pads allowed)
				(copperpour not_allowed)
				(footprints allowed)
			)
			(placement
				(enabled no)
				(sheetname "")
			)
			(fill
				(thermal_gap 0.5)
				(thermal_bridge_width 0.5)
				(island_removal_mode 0)
			)
			(polygon
				(pts
					(xy 27.2542 -90.9828) (xy 27.8638 -90.9828) (xy 27.8638 -91.1352) (xy 27.2542 -91.1352)
				)
			)
		)
		(zone
			(layer "B.Cu")
			(hatch none 0.5)
			(connect_pads
				(clearance 0)
			)
			(min_thickness 0.25)
			(keepout
				(tracks not_allowed)
				(vias allowed)
				(pads allowed)
				(copperpour not_allowed)
				(footprints allowed)
			)
			(placement
				(enabled no)
				(sheetname "")
			)
			(fill
				(thermal_gap 0.5)
				(thermal_bridge_width 0.5)
				(island_removal_mode 0)
			)
			(polygon
				(pts
					(xy 27.2542 -90.9828) (xy 27.8638 -90.9828) (xy 27.8638 -91.1352) (xy 27.2542 -91.1352)
				)
			)
		)
	)
	(footprint ""
		(layer "B.Cu")
		(at 124.587 -42.545 180)
		(property "Reference" "R218"
			(at -3.429 -0.16637 0)
			(unlocked yes)
			(layer "B.SilkS")
			(effects
				(font
					(size 0.7874 0.5842)
					(thickness 0.1524)
				)
				(justify mirror)
			)
		)
		(property "Value" "VAL*"
			(at -0.02032 2.13233 180)
			(unlocked yes)
			(layer "B.Fab")
			(hide yes)
			(effects
				(font
					(size 0.7874 0.5842)
					(thickness 0.1524)
				)
				(justify mirror)
			)
		)
		(property "Tolerance" "TOL*"
			(at -0.044704 3.05435 180)
			(unlocked yes)
			(layer "Cmts.User")
			(hide yes)
			(effects
				(font
					(size 0.7874 0.5842)
					(thickness 0.1524)
				)
				(justify mirror)
			)
		)
		(property "User Part Number" "PARTNUM*"
			(at -0.02032 4.024884 180)
			(unlocked yes)
			(layer "Cmts.User")
			(hide yes)
			(effects
				(font
					(size 0.7874 0.5842)
					(thickness 0.1524)
				)
				(justify mirror)
			)
		)
		(property "Device Type" "RESISTOR-G155-11000-01,100OHM,A"
			(at -0.008382 1.210564 180)
			(unlocked yes)
			(layer "B.Fab")
			(hide yes)
			(effects
				(font
					(size 0.7874 0.5842)
					(thickness 0.1524)
				)
				(justify mirror)
			)
		)
		(duplicate_pad_numbers_are_jumpers no)
		(fp_line
			(start 1.143 0.5588)
			(end -1.143 0.5588)
			(stroke
				(width 0.1)
				(type default)
			)
			(layer "B.SilkS")
		)
		(fp_line
			(start 1.143 -0.5588)
			(end 1.143 0.5588)
			(stroke
				(width 0.1)
				(type default)
			)
			(layer "B.SilkS")
		)
		(fp_line
			(start -1.143 0.5588)
			(end -1.143 -0.5588)
			(stroke
				(width 0.1)
				(type default)
			)
			(layer "B.SilkS")
		)
		(fp_line
			(start -1.143 -0.5588)
			(end 1.143 -0.5588)
			(stroke
				(width 0.1)
				(type default)
			)
			(layer "B.SilkS")
		)
		(fp_rect
			(start 1.143 0.5588)
			(end -1.143 -0.5588)
			(stroke
				(width 0)
				(type default)
			)
			(fill no)
			(layer "B.CrtYd")
		)
		(fp_line
			(start 0.508 0.3048)
			(end -0.508 0.3048)
			(stroke
				(width 0.1)
				(type default)
			)
			(layer "B.Fab")
		)
		(fp_line
			(start 0.508 -0.3048)
			(end 0.508 0.3048)
			(stroke
				(width 0.1)
				(type default)
			)
			(layer "B.Fab")
		)
		(fp_line
			(start -0.508 0.3048)
			(end -0.508 -0.3048)
			(stroke
				(width 0.1)
				(type default)
			)
			(layer "B.Fab")
		)
		(fp_line
			(start -0.508 -0.3048)
			(end 0.508 -0.3048)
			(stroke
				(width 0.1)
				(type default)
			)
			(layer "B.Fab")
		)
		(pad "1" smd rect
			(at 0.5334 0)
			(size 0.7112 0.6096)
			(layers "B.Cu" "B.Mask" "B.Paste")
			(net "FPGA_M1")
		)
		(pad "2" smd rect
			(at -0.5334 0)
			(size 0.7112 0.6096)
			(layers "B.Cu" "B.Mask" "B.Paste")
			(net "SG")
		)
		(zone
			(layer "B.Cu")
			(hatch none 0.5)
			(connect_pads
				(clearance 0)
			)
			(min_thickness 0.25)
			(keepout
				(tracks allowed)
				(vias not_allowed)
				(pads allowed)
				(copperpour not_allowed)
				(footprints allowed)
			)
			(placement
				(enabled no)
				(sheetname "")
			)
			(fill
				(thermal_gap 0.5)
				(thermal_bridge_width 0.5)
				(island_removal_mode 0)
			)
			(polygon
				(pts
					(xy 124.5108 -42.8498) (xy 124.5108 -42.2402) (xy 124.6632 -42.2402) (xy 124.6632 -42.8498)
				)
			)
		)
	)
	(footprint ""
		(layer "B.Cu")
		(at 155.956 -107.696 90)
		(property "Reference" "R280"
			(at 0.381 1.23063 270)
			(unlocked yes)
			(layer "B.SilkS")
			(effects
				(font
					(size 0.7874 0.5842)
					(thickness 0.1524)
				)
				(justify mirror)
			)
		)
		(property "Value" "VAL*"
			(at -0.02032 2.13233 90)
			(unlocked yes)
			(layer "B.Fab")
			(hide yes)
			(effects
				(font
					(size 0.7874 0.5842)
					(thickness 0.1524)
				)
				(justify mirror)
			)
		)
		(property "Tolerance" "TOL*"
			(at -0.044704 3.05435 90)
			(unlocked yes)
			(layer "Cmts.User")
			(hide yes)
			(effects
				(font
					(size 0.7874 0.5842)
					(thickness 0.1524)
				)
				(justify mirror)
			)
		)
		(property "User Part Number" "PARTNUM*"
			(at -0.02032 4.024884 90)
			(unlocked yes)
			(layer "Cmts.User")
			(hide yes)
			(effects
				(font
					(size 0.7874 0.5842)
					(thickness 0.1524)
				)
				(justify mirror)
			)
		)
		(property "Device Type" "RESISTOR-G155-13300-01,330OHM,A"
			(at -0.008382 1.210564 90)
			(unlocked yes)
			(layer "B.Fab")
			(hide yes)
			(effects
				(font
					(size 0.7874 0.5842)
					(thickness 0.1524)
				)
				(justify mirror)
			)
		)
		(duplicate_pad_numbers_are_jumpers no)
		(fp_line
			(start 1.143 -0.5588)
			(end 1.143 0.5588)
			(stroke
				(width 0.1)
				(type default)
			)
			(layer "B.SilkS")
		)
		(fp_line
			(start -1.143 -0.5588)
			(end 1.143 -0.5588)
			(stroke
				(width 0.1)
				(type default)
			)
			(layer "B.SilkS")
		)
		(fp_line
			(start 1.143 0.5588)
			(end -1.143 0.5588)
			(stroke
				(width 0.1)
				(type default)
			)
			(layer "B.SilkS")
		)
		(fp_line
			(start -1.143 0.5588)
			(end -1.143 -0.5588)
			(stroke
				(width 0.1)
				(type default)
			)
			(layer "B.SilkS")
		)
		(fp_rect
			(start -1.143 -0.5588)
			(end 1.143 0.5588)
			(stroke
				(width 0)
				(type default)
			)
			(fill no)
			(layer "B.CrtYd")
		)
		(fp_line
			(start 0.508 -0.3048)
			(end 0.508 0.3048)
			(stroke
				(width 0.1)
				(type default)
			)
			(layer "B.Fab")
		)
		(fp_line
			(start -0.508 -0.3048)
			(end 0.508 -0.3048)
			(stroke
				(width 0.1)
				(type default)
			)
			(layer "B.Fab")
		)
		(fp_line
			(start 0.508 0.3048)
			(end -0.508 0.3048)
			(stroke
				(width 0.1)
				(type default)
			)
			(layer "B.Fab")
		)
		(fp_line
			(start -0.508 0.3048)
			(end -0.508 -0.3048)
			(stroke
				(width 0.1)
				(type default)
			)
			(layer "B.Fab")
		)
		(pad "1" smd rect
			(at 0.5334 0 270)
			(size 0.7112 0.6096)
			(layers "B.Cu" "B.Mask" "B.Paste")
			(net "UNNAMED_14_OPTICAL_I139_A")
		)
		(pad "2" smd rect
			(at -0.5334 0 270)
			(size 0.7112 0.6096)
			(layers "B.Cu" "B.Mask" "B.Paste")
			(net "XP3R3V_FPGA")
		)
		(zone
			(layer "B.Cu")
			(hatch none 0.5)
			(connect_pads
				(clearance 0)
			)
			(min_thickness 0.25)
			(keepout
				(tracks allowed)
				(vias not_allowed)
				(pads allowed)
				(copperpour not_allowed)
				(footprints allowed)
			)
			(placement
				(enabled no)
				(sheetname "")
			)
			(fill
				(thermal_gap 0.5)
				(thermal_bridge_width 0.5)
				(island_removal_mode 0)
			)
			(polygon
				(pts
					(xy 155.6512 -107.6198) (xy 156.2608 -107.6198) (xy 156.2608 -107.7722) (xy 155.6512 -107.7722)
				)
			)
		)
	)
)
